# SCM (Grand Teton) — schematic netlist excerpt (pin names and nets, part order shuffled) for the footprints in the layout excerpt that follows; sources: Cadence DE-HDL packaged netlist, KiCad conversion of 12092022_DA0F0TMDCD0_F0T_Management_Board_D_brd_V3_OCP.brd

C128  Q_CAP  1UF 25V 10% X6S  pkg C0402  page 17 : A = P1V8_STBY_DP_VCC18A ; B = GND
C229  Q_CAP  0.22UF 16V 10% EMPTY  pkg 0402  page 20 : A = M_BMC_DDR4_MCLK_C ; B = P1V2_AUX

(kicad_pcb
	(version 20260206)
	(generator "pcbnew")
	(generator_version "10.0")
	(general
		(thickness 1.6)
		(legacy_teardrops no)
	)
	(paper "A4")
	(title_block
		(title "12092022_DA0F0TMDCD0_F0T_Management_Board_D_brd_V3_OCP.brd")
		(comment 1 "Grand Teton / footprints 1078-1079 of 1440")
	)
	(layers
		(0 "F.Cu" signal "TOP")
		(4 "In1.Cu" signal "GND")
		(6 "In2.Cu" signal "IN1")
		(8 "In3.Cu" signal "GND1")
		(10 "In4.Cu" signal "IN2")
		(12 "In5.Cu" signal "VCC")
		(14 "In6.Cu" signal "VCC1")
		(16 "In7.Cu" signal "IN3")
		(18 "In8.Cu" signal "GND2")
		(20 "In9.Cu" signal "IN4")
		(22 "In10.Cu" signal "GND3")
		(2 "B.Cu" signal "BOTTOM")
		(9 "F.Adhes" user "F.Adhesive")
		(11 "B.Adhes" user "B.Adhesive")
		(13 "F.Paste" user "Package Geometry/Pastemask Top")
		(15 "B.Paste" user "Package Geometry/Pastemask Bottom")
		(5 "F.SilkS" user "Ref Des/Silkscreen Top")
		(7 "B.SilkS" user "Ref Des/Silkscreen Bottom")
		(1 "F.Mask" user "Board Geometry/Soldermask Top")
		(3 "B.Mask" user "Board Geometry/Soldermask Bottom")
		(17 "Dwgs.User" user "User.Drawings")
		(19 "Cmts.User" user "User.Comments")
		(21 "Eco1.User" user "User.Eco1")
		(23 "Eco2.User" user "User.Eco2")
		(25 "Edge.Cuts" user "Board Geometry/Outline")
		(27 "Margin" user)
		(31 "F.CrtYd" user "Package Geometry/Place Bound Top")
		(29 "B.CrtYd" user "Package Geometry/Place Bound Bottom")
		(35 "F.Fab" user "Ref Des/Assembly Top")
		(33 "B.Fab" user "Ref Des/Assembly Bottom")
	)
	(footprint ""
		(layer "B.Cu")
		(at 77.598778 -48.63084 -90)
		(property "Reference" "C229"
			(at 0 0 90)
			(layer "B.SilkS")
			(hide yes)
			(effects
				(font
					(size 1.27 1.27)
				)
				(justify mirror)
			)
		)
		(property "Value" ""
			(at 0 0 90)
			(layer "B.Fab")
			(effects
				(font
					(size 1.27 1.27)
				)
				(justify mirror)
			)
		)
		(duplicate_pad_numbers_are_jumpers no)
		(fp_line
			(start -0.7874 0.4064)
			(end 0.7874 0.4064)
			(stroke
				(width 0.1524)
				(type default)
			)
			(layer "B.SilkS")
		)
		(fp_line
			(start 0.7874 0.4064)
			(end 0.7874 -0.4064)
			(stroke
				(width 0.1524)
				(type default)
			)
			(layer "B.SilkS")
		)
		(fp_line
			(start -0.7874 -0.4064)
			(end -0.7874 0.4064)
			(stroke
				(width 0.1524)
				(type default)
			)
			(layer "B.SilkS")
		)
		(fp_line
			(start 0.7874 -0.4064)
			(end -0.7874 -0.4064)
			(stroke
				(width 0.1524)
				(type default)
			)
			(layer "B.SilkS")
		)
		(fp_line
			(start -0.67945 0.3048)
			(end -0.120396 0.3048)
			(stroke
				(width 0.1)
				(type default)
			)
			(layer "B.Fab")
		)
		(fp_line
			(start -0.120396 0.3048)
			(end -0.120396 0.2794)
			(stroke
				(width 0.1)
				(type default)
			)
			(layer "B.Fab")
		)
		(fp_line
			(start 0.12065 0.3048)
			(end 0.67945 0.3048)
			(stroke
				(width 0.1)
				(type default)
			)
			(layer "B.Fab")
		)
		(fp_line
			(start 0.67945 0.3048)
			(end 0.67945 -0.305054)
			(stroke
				(width 0.1)
				(type default)
			)
			(layer "B.Fab")
		)
		(fp_line
			(start -0.120396 0.2794)
			(end 0.12065 0.2794)
			(stroke
				(width 0.1)
				(type default)
			)
			(layer "B.Fab")
		)
		(fp_line
			(start 0.12065 0.2794)
			(end 0.12065 0.3048)
			(stroke
				(width 0.1)
				(type default)
			)
			(layer "B.Fab")
		)
		(fp_line
			(start -0.12065 -0.2794)
			(end -0.12065 -0.3048)
			(stroke
				(width 0.1)
				(type default)
			)
			(layer "B.Fab")
		)
		(fp_line
			(start 0.12065 -0.2794)
			(end -0.12065 -0.2794)
			(stroke
				(width 0.1)
				(type default)
			)
			(layer "B.Fab")
		)
		(fp_line
			(start -0.67945 -0.3048)
			(end -0.67945 0.3048)
			(stroke
				(width 0.1)
				(type default)
			)
			(layer "B.Fab")
		)
		(fp_line
			(start -0.12065 -0.3048)
			(end -0.67945 -0.3048)
			(stroke
				(width 0.1)
				(type default)
			)
			(layer "B.Fab")
		)
		(fp_line
			(start 0.12065 -0.305054)
			(end 0.12065 -0.2794)
			(stroke
				(width 0.1)
				(type default)
			)
			(layer "B.Fab")
		)
		(fp_line
			(start 0.67945 -0.305054)
			(end 0.12065 -0.305054)
			(stroke
				(width 0.1)
				(type default)
			)
			(layer "B.Fab")
		)
		(pad "1" smd circle
			(at 0.40005 0 90)
			(size 0 0)
			(layers "B.Cu" "B.Mask" "B.Paste")
			(net "M_BMC_DDR4_MCLK_C")
		)
		(pad "2" smd circle
			(at -0.40005 0 90)
			(size 0 0)
			(layers "B.Cu" "B.Mask" "B.Paste")
			(net "P1V2_AUX")
		)
	)
	(footprint ""
		(layer "B.Cu")
		(at 71.979282 -62.776608 90)
		(property "Reference" "C128"
			(at 0 0 90)
			(layer "B.SilkS")
			(hide yes)
			(effects
				(font
					(size 1.27 1.27)
				)
				(justify mirror)
			)
		)
		(property "Value" ""
			(at 0 0 90)
			(layer "B.Fab")
			(effects
				(font
					(size 1.27 1.27)
				)
				(justify mirror)
			)
		)
		(duplicate_pad_numbers_are_jumpers no)
		(fp_line
			(start 0.7874 -0.4064)
			(end -0.7874 -0.4064)
			(stroke
				(width 0.1524)
				(type default)
			)
			(layer "B.SilkS")
		)
		(fp_line
			(start -0.7874 -0.4064)
			(end -0.7874 0.4064)
			(stroke
				(width 0.1524)
				(type default)
			)
			(layer "B.SilkS")
		)
		(fp_line
			(start 0.7874 0.4064)
			(end 0.7874 -0.4064)
			(stroke
				(width 0.1524)
				(type default)
			)
			(layer "B.SilkS")
		)
		(fp_line
			(start -0.7874 0.4064)
			(end 0.7874 0.4064)
			(stroke
				(width 0.1524)
				(type default)
			)
			(layer "B.SilkS")
		)
		(fp_line
			(start 0.67945 -0.305054)
			(end 0.12065 -0.305054)
			(stroke
				(width 0.1)
				(type default)
			)
			(layer "B.Fab")
		)
		(fp_line
			(start 0.12065 -0.305054)
			(end 0.12065 -0.2794)
			(stroke
				(width 0.1)
				(type default)
			)
			(layer "B.Fab")
		)
		(fp_line
			(start -0.12065 -0.3048)
			(end -0.67945 -0.3048)
			(stroke
				(width 0.1)
				(type default)
			)
			(layer "B.Fab")
		)
		(fp_line
			(start -0.67945 -0.3048)
			(end -0.67945 0.3048)
			(stroke
				(width 0.1)
				(type default)
			)
			(layer "B.Fab")
		)
		(fp_line
			(start 0.12065 -0.2794)
			(end -0.12065 -0.2794)
			(stroke
				(width 0.1)
				(type default)
			)
			(layer "B.Fab")
		)
		(fp_line
			(start -0.12065 -0.2794)
			(end -0.12065 -0.3048)
			(stroke
				(width 0.1)
				(type default)
			)
			(layer "B.Fab")
		)
		(fp_line
			(start 0.12065 0.2794)
			(end 0.12065 0.3048)
			(stroke
				(width 0.1)
				(type default)
			)
			(layer "B.Fab")
		)
		(fp_line
			(start -0.120396 0.2794)
			(end 0.12065 0.2794)
			(stroke
				(width 0.1)
				(type default)
			)
			(layer "B.Fab")
		)
		(fp_line
			(start 0.67945 0.3048)
			(end 0.67945 -0.305054)
			(stroke
				(width 0.1)
				(type default)
			)
			(layer "B.Fab")
		)
		(fp_line
			(start 0.12065 0.3048)
			(end 0.67945 0.3048)
			(stroke
				(width 0.1)
				(type default)
			)
			(layer "B.Fab")
		)
		(fp_line
			(start -0.120396 0.3048)
			(end -0.120396 0.2794)
			(stroke
				(width 0.1)
				(type default)
			)
			(layer "B.Fab")
		)
		(fp_line
			(start -0.67945 0.3048)
			(end -0.120396 0.3048)
			(stroke
				(width 0.1)
				(type default)
			)
			(layer "B.Fab")
		)
		(pad "1" smd circle
			(at 0.40005 0 270)
			(size 0 0)
			(layers "B.Cu" "B.Mask" "B.Paste")
			(net "P1V8_STBY_DP_VCC18A")
		)
		(pad "2" smd circle
			(at -0.40005 0 270)
			(size 0 0)
			(layers "B.Cu" "B.Mask" "B.Paste")
			(net "GND")
		)
	)
)
